(kicad_pcb
	(version 20260206)
	(generator "pcbnew")
	(generator_version "10.0")
	(general
		(thickness 1.6)
		(legacy_teardrops no)
	)
	(paper "A4")
	(title_block
		(title "03242023_DA0F0TMBIJ0_F0T_Motherboard_J_brd_V01_OCP.brd")
		(comment 1 "Grand Teton / footprints 2372-2377 of 6105")
	)
	(layers
		(0 "F.Cu" signal "TOP")
		(4 "In1.Cu" signal "GND")
		(6 "In2.Cu" signal "IN1")
		(8 "In3.Cu" signal "GND1")
		(10 "In4.Cu" signal "IN2")
		(12 "In5.Cu" signal "GND2")
		(14 "In6.Cu" signal "IN3")
		(16 "In7.Cu" signal "GND3")
		(18 "In8.Cu" signal "VCC")
		(20 "In9.Cu" signal "VCC1")
		(22 "In10.Cu" signal "GND4")
		(24 "In11.Cu" signal "IN4")
		(26 "In12.Cu" signal "GND5")
		(28 "In13.Cu" signal "IN5")
		(30 "In14.Cu" signal "GND6")
		(32 "In15.Cu" signal "IN6")
		(34 "In16.Cu" signal "GND7")
		(2 "B.Cu" signal "BOTTOM")
		(9 "F.Adhes" user "F.Adhesive")
		(11 "B.Adhes" user "B.Adhesive")
		(13 "F.Paste" user "Package Geometry/Pastemask Top")
		(15 "B.Paste" user "Package Geometry/Pastemask Bottom")
		(5 "F.SilkS" user "Ref Des/Silkscreen Top")
		(7 "B.SilkS" user "Ref Des/Silkscreen Bottom")
		(1 "F.Mask" user "Board Geometry/Soldermask Top")
		(3 "B.Mask" user "Board Geometry/Soldermask Bottom")
		(17 "Dwgs.User" user "User.Drawings")
		(19 "Cmts.User" user "User.Comments")
		(21 "Eco1.User" user "User.Eco1")
		(23 "Eco2.User" user "User.Eco2")
		(25 "Edge.Cuts" user "Board Geometry/Outline")
		(27 "Margin" user)
		(31 "F.CrtYd" user "Package Geometry/Place Bound Top")
		(29 "B.CrtYd" user "Package Geometry/Place Bound Bottom")
		(35 "F.Fab" user "Ref Des/Assembly Top")
		(33 "B.Fab" user "Ref Des/Assembly Bottom")
	)
	(footprint ""
		(layer "F.Cu")
		(at 36.84143 -176.480978)
		(property "Reference" "PC1285"
			(at 0 0 0)
			(layer "F.SilkS")
			(hide yes)
			(effects
				(font
					(size 1.27 1.27)
				)
			)
		)
		(property "Value" ""
			(at 0 0 0)
			(layer "F.Fab")
			(effects
				(font
					(size 1.27 1.27)
				)
			)
		)
		(duplicate_pad_numbers_are_jumpers no)
		(fp_line
			(start -1.524 -0.762)
			(end 1.524 -0.762)
			(stroke
				(width 0.1524)
				(type default)
			)
			(layer "F.SilkS")
		)
		(fp_line
			(start -1.524 0.762)
			(end -1.524 -0.762)
			(stroke
				(width 0.1524)
				(type default)
			)
			(layer "F.SilkS")
		)
		(fp_line
			(start 1.524 -0.762)
			(end 1.524 0.762)
			(stroke
				(width 0.1524)
				(type default)
			)
			(layer "F.SilkS")
		)
		(fp_line
			(start 1.524 0.762)
			(end -1.524 0.762)
			(stroke
				(width 0.1524)
				(type default)
			)
			(layer "F.SilkS")
		)
		(fp_line
			(start -1.1049 -0.724916)
			(end -1.1049 0.724916)
			(stroke
				(width 0.1)
				(type default)
			)
			(layer "F.Fab")
		)
		(fp_line
			(start -1.1049 0.724916)
			(end 1.1049 0.724916)
			(stroke
				(width 0.1)
				(type default)
			)
			(layer "F.Fab")
		)
		(fp_line
			(start 1.1049 -0.724916)
			(end -1.1049 -0.724916)
			(stroke
				(width 0.1)
				(type default)
			)
			(layer "F.Fab")
		)
		(fp_line
			(start 1.1049 0.724916)
			(end 1.1049 -0.724916)
			(stroke
				(width 0.1)
				(type default)
			)
			(layer "F.Fab")
		)
		(pad "1" smd rect
			(at -0.889 0 180)
			(size 1.016 1.27)
			(layers "F.Cu" "F.Mask" "F.Paste")
			(net "PVNN_MAIN_CPU1")
		)
		(pad "2" smd rect
			(at 0.889 0 180)
			(size 1.016 1.27)
			(layers "F.Cu" "F.Mask" "F.Paste")
			(net "GND")
		)
	)
	(footprint ""
		(layer "F.Cu")
		(at 329.240388 0.383794 180)
		(property "Reference" "J83"
			(at -4.415282 -1.140206 90)
			(unlocked yes)
			(layer "F.SilkS")
			(effects
				(font
					(size 0.7874 0.5842)
					(thickness 0.1524)
				)
				(justify left)
			)
		)
		(property "Value" ""
			(at 0 0 180)
			(layer "F.Fab")
			(effects
				(font
					(size 1.27 1.27)
				)
			)
		)
		(duplicate_pad_numbers_are_jumpers no)
		(fp_line
			(start 1.2192 2.1082)
			(end -1.2192 2.1082)
			(stroke
				(width 0.1524)
				(type default)
			)
			(layer "F.SilkS")
		)
		(fp_line
			(start 1.2192 -2.1082)
			(end 1.2192 2.1082)
			(stroke
				(width 0.1524)
				(type default)
			)
			(layer "F.SilkS")
		)
		(fp_line
			(start -1.2192 2.1082)
			(end -1.2192 -2.1082)
			(stroke
				(width 0.1524)
				(type default)
			)
			(layer "F.SilkS")
		)
		(fp_line
			(start -1.2192 -2.1082)
			(end 1.2192 -2.1082)
			(stroke
				(width 0.1524)
				(type default)
			)
			(layer "F.SilkS")
		)
		(pad "" np_thru_hole circle
			(at -2.8829 -1.27 90)
			(size 1.0414 1.0414)
			(drill 1.0414)
			(layers "*.Cu" "*.Mask")
			(clearance 0.381)
			(thermal_gap 0.381)
		)
		(pad "" np_thru_hole circle
			(at -2.8829 1.27 90)
			(size 1.0414 1.0414)
			(drill 1.0414)
			(layers "*.Cu" "*.Mask")
			(clearance 0.381)
			(thermal_gap 0.381)
		)
		(pad "" np_thru_hole circle
			(at 3.4671 -1.27 90)
			(size 1.0414 1.0414)
			(drill 1.0414)
			(layers "*.Cu" "*.Mask")
			(clearance 0.381)
			(thermal_gap 0.381)
		)
		(pad "" np_thru_hole circle
			(at 3.4671 1.27 90)
			(size 1.0414 1.0414)
			(drill 1.0414)
			(layers "*.Cu" "*.Mask")
			(clearance 0.381)
			(thermal_gap 0.381)
		)
		(pad "1" smd rect
			(at 0.8255 -0.249936 90)
			(size 0.3048 0.508)
			(layers "F.Cu" "F.Mask" "F.Paste")
			(net "DELTA_L_85_10INCH_IN1_DN")
		)
		(pad "2" smd rect
			(at 0.8255 0.249936 90)
			(size 0.3048 0.508)
			(layers "F.Cu" "F.Mask" "F.Paste")
			(net "DELTA_L_85_10INCH_IN1_DP")
		)
		(pad "3" smd circle
			(at 0 0 180)
			(size 0 0)
			(layers "F.Cu" "F.Mask" "F.Paste")
			(net "DELTA_L_GND_1")
		)
		(zone
			(layer "F.Cu")
			(hatch none 0.5)
			(connect_pads
				(clearance 0)
			)
			(min_thickness 0.25)
			(keepout
				(tracks not_allowed)
				(vias allowed)
				(pads allowed)
				(copperpour not_allowed)
				(footprints allowed)
			)
			(placement
				(enabled no)
				(sheetname "")
			)
			(fill
				(thermal_gap 0.5)
				(thermal_bridge_width 0.5)
				(island_removal_mode 0)
			)
			(polygon
				(pts
					(xy 328.122788 0.932434) (xy 328.122788 0.83693) (xy 328.719688 0.83693) (xy 328.719688 0.43053)
					(xy 328.122788 0.43053) (xy 328.122788 0.337058) (xy 328.719688 0.337058) (xy 328.719688 -0.069342)
					(xy 328.122788 -0.069342) (xy 328.122788 -0.164846) (xy 328.821288 -0.164846) (xy 328.821288 0.932434)
				)
			)
		)
		(zone
			(layers "F.Cu" "B.Cu" "In1.Cu" "In2.Cu" "In3.Cu" "In4.Cu" "In5.Cu" "In6.Cu"
				"In7.Cu" "In8.Cu" "In9.Cu" "In10.Cu" "In11.Cu" "In12.Cu" "In13.Cu" "In14.Cu"
				"In15.Cu" "In16.Cu"
			)
			(hatch none 0.5)
			(connect_pads
				(clearance 0)
			)
			(min_thickness 0.25)
			(keepout
				(tracks not_allowed)
				(vias allowed)
				(pads allowed)
				(copperpour not_allowed)
				(footprints allowed)
			)
			(placement
				(enabled no)
				(sheetname "")
			)
			(fill
				(thermal_gap 0.5)
				(thermal_bridge_width 0.5)
				(island_removal_mode 0)
			)
			(polygon
				(pts
					(arc
						(start 326.700388 -0.886206)
						(mid 324.846188 -0.886206)
						(end 326.700388 -0.886206)
					)
				)
			)
		)
		(zone
			(layers "F.Cu" "B.Cu" "In1.Cu" "In2.Cu" "In3.Cu" "In4.Cu" "In5.Cu" "In6.Cu"
				"In7.Cu" "In8.Cu" "In9.Cu" "In10.Cu" "In11.Cu" "In12.Cu" "In13.Cu" "In14.Cu"
				"In15.Cu" "In16.Cu"
			)
			(hatch none 0.5)
			(connect_pads
				(clearance 0)
			)
			(min_thickness 0.25)
			(keepout
				(tracks not_allowed)
				(vias allowed)
				(pads allowed)
				(copperpour not_allowed)
				(footprints allowed)
			)
			(placement
				(enabled no)
				(sheetname "")
			)
			(fill
				(thermal_gap 0.5)
				(thermal_bridge_width 0.5)
				(island_removal_mode 0)
			)
			(polygon
				(pts
					(arc
						(start 326.700388 1.653794)
						(mid 324.846188 1.653794)
						(end 326.700388 1.653794)
					)
				)
			)
		)
		(zone
			(layers "F.Cu" "B.Cu" "In1.Cu" "In2.Cu" "In3.Cu" "In4.Cu" "In5.Cu" "In6.Cu"
				"In7.Cu" "In8.Cu" "In9.Cu" "In10.Cu" "In11.Cu" "In12.Cu" "In13.Cu" "In14.Cu"
				"In15.Cu" "In16.Cu"
			)
			(hatch none 0.5)
			(connect_pads
				(clearance 0)
			)
			(min_thickness 0.25)
			(keepout
				(tracks not_allowed)
				(vias allowed)
				(pads allowed)
				(copperpour not_allowed)
				(footprints allowed)
			)
			(placement
				(enabled no)
				(sheetname "")
			)
			(fill
				(thermal_gap 0.5)
				(thermal_bridge_width 0.5)
				(island_removal_mode 0)
			)
			(polygon
				(pts
					(arc
						(start 333.050388 -0.886206)
						(mid 331.196188 -0.886206)
						(end 333.050388 -0.886206)
					)
				)
			)
		)
		(zone
			(layers "F.Cu" "B.Cu" "In1.Cu" "In2.Cu" "In3.Cu" "In4.Cu" "In5.Cu" "In6.Cu"
				"In7.Cu" "In8.Cu" "In9.Cu" "In10.Cu" "In11.Cu" "In12.Cu" "In13.Cu" "In14.Cu"
				"In15.Cu" "In16.Cu"
			)
			(hatch none 0.5)
			(connect_pads
				(clearance 0)
			)
			(min_thickness 0.25)
			(keepout
				(tracks not_allowed)
				(vias allowed)
				(pads allowed)
				(copperpour not_allowed)
				(footprints allowed)
			)
			(placement
				(enabled no)
				(sheetname "")
			)
			(fill
				(thermal_gap 0.5)
				(thermal_bridge_width 0.5)
				(island_removal_mode 0)
			)
			(polygon
				(pts
					(arc
						(start 333.050388 1.653794)
						(mid 331.196188 1.653794)
						(end 333.050388 1.653794)
					)
				)
			)
		)
	)
	(footprint ""
		(layer "F.Cu")
		(at 24.069802 -411.434534)
		(property "Reference" "R3487"
			(at 0 0 0)
			(layer "F.SilkS")
			(hide yes)
			(effects
				(font
					(size 1.27 1.27)
				)
			)
		)
		(property "Value" ""
			(at 0 0 0)
			(layer "F.Fab")
			(effects
				(font
					(size 1.27 1.27)
				)
			)
		)
		(duplicate_pad_numbers_are_jumpers no)
		(fp_line
			(start -0.7874 -0.4064)
			(end 0.7874 -0.4064)
			(stroke
				(width 0.1524)
				(type default)
			)
			(layer "F.SilkS")
		)
		(fp_line
			(start -0.7874 0.4064)
			(end -0.7874 -0.4064)
			(stroke
				(width 0.1524)
				(type default)
			)
			(layer "F.SilkS")
		)
		(fp_line
			(start 0.7874 -0.4064)
			(end 0.7874 0.4064)
			(stroke
				(width 0.1524)
				(type default)
			)
			(layer "F.SilkS")
		)
		(fp_line
			(start 0.7874 0.4064)
			(end -0.7874 0.4064)
			(stroke
				(width 0.1524)
				(type default)
			)
			(layer "F.SilkS")
		)
		(fp_line
			(start -0.67945 -0.305054)
			(end -0.12065 -0.305054)
			(stroke
				(width 0.1)
				(type default)
			)
			(layer "F.Fab")
		)
		(fp_line
			(start -0.67945 0.3048)
			(end -0.67945 -0.305054)
			(stroke
				(width 0.1)
				(type default)
			)
			(layer "F.Fab")
		)
		(fp_line
			(start -0.12065 -0.305054)
			(end -0.12065 -0.2794)
			(stroke
				(width 0.1)
				(type default)
			)
			(layer "F.Fab")
		)
		(fp_line
			(start -0.12065 -0.2794)
			(end 0.12065 -0.2794)
			(stroke
				(width 0.1)
				(type default)
			)
			(layer "F.Fab")
		)
		(fp_line
			(start -0.12065 0.2794)
			(end -0.12065 0.3048)
			(stroke
				(width 0.1)
				(type default)
			)
			(layer "F.Fab")
		)
		(fp_line
			(start -0.12065 0.3048)
			(end -0.67945 0.3048)
			(stroke
				(width 0.1)
				(type default)
			)
			(layer "F.Fab")
		)
		(fp_line
			(start 0.120396 0.2794)
			(end -0.12065 0.2794)
			(stroke
				(width 0.1)
				(type default)
			)
			(layer "F.Fab")
		)
		(fp_line
			(start 0.120396 0.3048)
			(end 0.120396 0.2794)
			(stroke
				(width 0.1)
				(type default)
			)
			(layer "F.Fab")
		)
		(fp_line
			(start 0.12065 -0.3048)
			(end 0.67945 -0.3048)
			(stroke
				(width 0.1)
				(type default)
			)
			(layer "F.Fab")
		)
		(fp_line
			(start 0.12065 -0.2794)
			(end 0.12065 -0.3048)
			(stroke
				(width 0.1)
				(type default)
			)
			(layer "F.Fab")
		)
		(fp_line
			(start 0.67945 -0.3048)
			(end 0.67945 0.3048)
			(stroke
				(width 0.1)
				(type default)
			)
			(layer "F.Fab")
		)
		(fp_line
			(start 0.67945 0.3048)
			(end 0.120396 0.3048)
			(stroke
				(width 0.1)
				(type default)
			)
			(layer "F.Fab")
		)
		(pad "1" smd circle
			(at -0.40005 0)
			(size 0 0)
			(layers "F.Cu" "F.Mask" "F.Paste")
			(net "P3V3_AUX")
		)
		(pad "2" smd circle
			(at 0.40005 0)
			(size 0 0)
			(layers "F.Cu" "F.Mask" "F.Paste")
			(net "GPU_PRSNT_N")
		)
	)
	(footprint ""
		(layer "F.Cu")
		(at 156.888434 -402.371052 -90)
		(property "Reference" "C767"
			(at 0 0 270)
			(layer "F.SilkS")
			(hide yes)
			(effects
				(font
					(size 1.27 1.27)
				)
			)
		)
		(property "Value" ""
			(at 0 0 270)
			(layer "F.Fab")
			(effects
				(font
					(size 1.27 1.27)
				)
			)
		)
		(duplicate_pad_numbers_are_jumpers no)
		(fp_line
			(start -0.299974 0.150114)
			(end -0.299974 -0.150114)
			(stroke
				(width 0.1)
				(type default)
			)
			(layer "F.Fab")
		)
		(fp_line
			(start 0.299974 0.150114)
			(end -0.299974 0.150114)
			(stroke
				(width 0.1)
				(type default)
			)
			(layer "F.Fab")
		)
		(fp_line
			(start -0.299974 -0.150114)
			(end 0.299974 -0.150114)
			(stroke
				(width 0.1)
				(type default)
			)
			(layer "F.Fab")
		)
		(fp_line
			(start 0.299974 -0.150114)
			(end 0.299974 0.150114)
			(stroke
				(width 0.1)
				(type default)
			)
			(layer "F.Fab")
		)
		(pad "1" smd rect
			(at -0.2667 0 270)
			(size 0.3048 0.381)
			(layers "F.Cu" "F.Mask" "F.Paste")
			(net "P5E_CPU1_PE2_TX_C_DP<3>")
		)
		(pad "2" smd rect
			(at 0.2667 0 270)
			(size 0.3048 0.381)
			(layers "F.Cu" "F.Mask" "F.Paste")
			(net "P5E_CPU1_PE2_TX_DP<3>")
		)
	)
	(footprint ""
		(layer "F.Cu")
		(at 265.029696 -72.262492 90)
		(property "Reference" "PC1219"
			(at 0 0 90)
			(layer "F.SilkS")
			(hide yes)
			(effects
				(font
					(size 1.27 1.27)
				)
			)
		)
		(property "Value" ""
			(at 0 0 90)
			(layer "F.Fab")
			(effects
				(font
					(size 1.27 1.27)
				)
			)
		)
		(duplicate_pad_numbers_are_jumpers no)
		(fp_line
			(start 0.7874 -0.4064)
			(end 0.7874 0.4064)
			(stroke
				(width 0.1524)
				(type default)
			)
			(layer "F.SilkS")
		)
		(fp_line
			(start -0.7874 -0.4064)
			(end 0.7874 -0.4064)
			(stroke
				(width 0.1524)
				(type default)
			)
			(layer "F.SilkS")
		)
		(fp_line
			(start 0.7874 0.4064)
			(end -0.7874 0.4064)
			(stroke
				(width 0.1524)
				(type default)
			)
			(layer "F.SilkS")
		)
		(fp_line
			(start -0.7874 0.4064)
			(end -0.7874 -0.4064)
			(stroke
				(width 0.1524)
				(type default)
			)
			(layer "F.SilkS")
		)
		(fp_line
			(start -0.12065 -0.305054)
			(end -0.12065 -0.2794)
			(stroke
				(width 0.1)
				(type default)
			)
			(layer "F.Fab")
		)
		(fp_line
			(start -0.67945 -0.305054)
			(end -0.12065 -0.305054)
			(stroke
				(width 0.1)
				(type default)
			)
			(layer "F.Fab")
		)
		(fp_line
			(start 0.67945 -0.3048)
			(end 0.67945 0.3048)
			(stroke
				(width 0.1)
				(type default)
			)
			(layer "F.Fab")
		)
		(fp_line
			(start 0.12065 -0.3048)
			(end 0.67945 -0.3048)
			(stroke
				(width 0.1)
				(type default)
			)
			(layer "F.Fab")
		)
		(fp_line
			(start 0.12065 -0.2794)
			(end 0.12065 -0.3048)
			(stroke
				(width 0.1)
				(type default)
			)
			(layer "F.Fab")
		)
		(fp_line
			(start -0.12065 -0.2794)
			(end 0.12065 -0.2794)
			(stroke
				(width 0.1)
				(type default)
			)
			(layer "F.Fab")
		)
		(fp_line
			(start 0.120396 0.2794)
			(end -0.12065 0.2794)
			(stroke
				(width 0.1)
				(type default)
			)
			(layer "F.Fab")
		)
		(fp_line
			(start -0.12065 0.2794)
			(end -0.12065 0.3048)
			(stroke
				(width 0.1)
				(type default)
			)
			(layer "F.Fab")
		)
		(fp_line
			(start 0.67945 0.3048)
			(end 0.120396 0.3048)
			(stroke
				(width 0.1)
				(type default)
			)
			(layer "F.Fab")
		)
		(fp_line
			(start 0.120396 0.3048)
			(end 0.120396 0.2794)
			(stroke
				(width 0.1)
				(type default)
			)
			(layer "F.Fab")
		)
		(fp_line
			(start -0.12065 0.3048)
			(end -0.67945 0.3048)
			(stroke
				(width 0.1)
				(type default)
			)
			(layer "F.Fab")
		)
		(fp_line
			(start -0.67945 0.3048)
			(end -0.67945 -0.305054)
			(stroke
				(width 0.1)
				(type default)
			)
			(layer "F.Fab")
		)
		(pad "1" smd circle
			(at -0.40005 0 90)
			(size 0 0)
			(layers "F.Cu" "F.Mask" "F.Paste")
			(net "SW_P12V_AUX_P1V05_PCH_AUX_FLT")
		)
		(pad "2" smd circle
			(at 0.40005 0 90)
			(size 0 0)
			(layers "F.Cu" "F.Mask" "F.Paste")
			(net "GND")
		)
	)
	(footprint ""
		(layer "F.Cu")
		(at 143.895318 -113.463324 180)
		(property "Reference" "R4758"
			(at 0 0 180)
			(layer "F.SilkS")
			(hide yes)
			(effects
				(font
					(size 1.27 1.27)
				)
			)
		)
		(property "Value" ""
			(at 0 0 180)
			(layer "F.Fab")
			(effects
				(font
					(size 1.27 1.27)
				)
			)
		)
		(duplicate_pad_numbers_are_jumpers no)
		(fp_line
			(start 0.7874 0.4064)
			(end -0.7874 0.4064)
			(stroke
				(width 0.1524)
				(type default)
			)
			(layer "F.SilkS")
		)
		(fp_line
			(start 0.7874 -0.4064)
			(end 0.7874 0.4064)
			(stroke
				(width 0.1524)
				(type default)
			)
			(layer "F.SilkS")
		)
		(fp_line
			(start -0.7874 0.4064)
			(end -0.7874 -0.4064)
			(stroke
				(width 0.1524)
				(type default)
			)
			(layer "F.SilkS")
		)
		(fp_line
			(start -0.7874 -0.4064)
			(end 0.7874 -0.4064)
			(stroke
				(width 0.1524)
				(type default)
			)
			(layer "F.SilkS")
		)
		(fp_line
			(start 0.67945 0.3048)
			(end 0.120396 0.3048)
			(stroke
				(width 0.1)
				(type default)
			)
			(layer "F.Fab")
		)
		(fp_line
			(start 0.67945 -0.3048)
			(end 0.67945 0.3048)
			(stroke
				(width 0.1)
				(type default)
			)
			(layer "F.Fab")
		)
		(fp_line
			(start 0.12065 -0.2794)
			(end 0.12065 -0.3048)
			(stroke
				(width 0.1)
				(type default)
			)
			(layer "F.Fab")
		)
		(fp_line
			(start 0.12065 -0.3048)
			(end 0.67945 -0.3048)
			(stroke
				(width 0.1)
				(type default)
			)
			(layer "F.Fab")
		)
		(fp_line
			(start 0.120396 0.3048)
			(end 0.120396 0.2794)
			(stroke
				(width 0.1)
				(type default)
			)
			(layer "F.Fab")
		)
		(fp_line
			(start 0.120396 0.2794)
			(end -0.12065 0.2794)
			(stroke
				(width 0.1)
				(type default)
			)
			(layer "F.Fab")
		)
		(fp_line
			(start -0.12065 0.3048)
			(end -0.67945 0.3048)
			(stroke
				(width 0.1)
				(type default)
			)
			(layer "F.Fab")
		)
		(fp_line
			(start -0.12065 0.2794)
			(end -0.12065 0.3048)
			(stroke
				(width 0.1)
				(type default)
			)
			(layer "F.Fab")
		)
		(fp_line
			(start -0.12065 -0.2794)
			(end 0.12065 -0.2794)
			(stroke
				(width 0.1)
				(type default)
			)
			(layer "F.Fab")
		)
		(fp_line
			(start -0.12065 -0.305054)
			(end -0.12065 -0.2794)
			(stroke
				(width 0.1)
				(type default)
			)
			(layer "F.Fab")
		)
		(fp_line
			(start -0.67945 0.3048)
			(end -0.67945 -0.305054)
			(stroke
				(width 0.1)
				(type default)
			)
			(layer "F.Fab")
		)
		(fp_line
			(start -0.67945 -0.305054)
			(end -0.12065 -0.305054)
			(stroke
				(width 0.1)
				(type default)
			)
			(layer "F.Fab")
		)
		(pad "1" smd circle
			(at -0.40005 0 180)
			(size 0 0)
			(layers "F.Cu" "F.Mask" "F.Paste")
			(net "OCP_V3_2_AUX_PWR_PLD_EN_R")
		)
		(pad "2" smd circle
			(at 0.40005 0 180)
			(size 0 0)
			(layers "F.Cu" "F.Mask" "F.Paste")
			(net "OCP_V3_2_AUX_PWR_EN_R2")
		)
	)
)
